(kicad_pcb
	(version 20241229)
	(generator "pcbnew")
	(generator_version "9.0")
	(general
		(thickness 1.711)
		(legacy_teardrops no)
	)
	(paper "A4")
	(title_block
		(title "Antmicro Baseboard for Jetson AGX Thor")
		(date "2026-02-18")
		(rev "1.1.0")
		(company "Antmicro Ltd")
		(comment 1 "www.antmicro.com")
		(comment 9 "footprints 46-50 of 1170")
	)
	(layers
		(0 "F.Cu" signal)
		(4 "In1.Cu" signal)
		(6 "In2.Cu" signal)
		(8 "In3.Cu" signal)
		(10 "In4.Cu" jumper)
		(12 "In5.Cu" signal)
		(14 "In6.Cu" signal)
		(16 "In7.Cu" signal)
		(18 "In8.Cu" signal)
		(2 "B.Cu" signal)
		(9 "F.Adhes" user "F.Adhesive")
		(11 "B.Adhes" user "B.Adhesive")
		(13 "F.Paste" user)
		(15 "B.Paste" user)
		(5 "F.SilkS" user "F.Silkscreen")
		(7 "B.SilkS" user "B.Silkscreen")
		(1 "F.Mask" user)
		(3 "B.Mask" user)
		(17 "Dwgs.User" user "User.Drawings")
		(19 "Cmts.User" user "User.Comments")
		(21 "Eco1.User" user "User.Eco1")
		(23 "Eco2.User" user "User.Eco2")
		(25 "Edge.Cuts" user)
		(27 "Margin" user)
		(31 "F.CrtYd" user "F.Courtyard")
		(29 "B.CrtYd" user "B.Courtyard")
		(35 "F.Fab" user)
		(33 "B.Fab" user)
	)
	(footprint "antmicro-footprints:C_0603_1608Metric_EIA"
		(layer "F.Cu")
		(at 147.954391 127.84 180)
		(descr "Capacitor SMD 0603, IPC-7351 Density Level A")
		(tags "Capacitor 0603")
		(property "Reference" "C305"
			(at -4.045609 0.34 0)
			(layer "F.SilkS")
			(effects
				(font
					(size 0.7 0.7)
					(thickness 0.15)
				)
				(justify right top)
			)
		)
		(property "Value" "C_22u_16V_0603"
			(at -1.42757 1.770288 0)
			(layer "F.Fab")
			(effects
				(font
					(size 0.7 0.7)
					(thickness 0.15)
				)
				(justify right top)
			)
		)
		(property "Datasheet" "https://product.samsungsem.com/mlcc/CL10A226MO7JZN.do"
			(at 0 0 0)
			(layer "F.Fab")
			(hide yes)
			(effects
				(font
					(size 1.27 1.27)
					(thickness 0.15)
				)
			)
		)
		(property "Description" "SMD Multilayer Ceramic Capacitor"
			(at 0 0 0)
			(layer "F.Fab")
			(hide yes)
			(effects
				(font
					(size 1.27 1.27)
					(thickness 0.15)
				)
			)
		)
		(property "Val" "22u"
			(at 0 0 180)
			(unlocked yes)
			(layer "F.Fab")
			(hide yes)
			(effects
				(font
					(size 1 1)
					(thickness 0.15)
				)
			)
		)
		(property "MPN" "CL10A226MO7JZNC"
			(at 0 0 180)
			(unlocked yes)
			(layer "F.Fab")
			(hide yes)
			(effects
				(font
					(size 1 1)
					(thickness 0.15)
				)
			)
		)
		(property "Manufacturer" "Samsung Electro-Mechanics"
			(at 0 0 180)
			(unlocked yes)
			(layer "F.Fab")
			(hide yes)
			(effects
				(font
					(size 1 1)
					(thickness 0.15)
				)
			)
		)
		(property "License" "Apache-2.0"
			(at 0 0 180)
			(unlocked yes)
			(layer "F.Fab")
			(hide yes)
			(effects
				(font
					(size 1 1)
					(thickness 0.15)
				)
			)
		)
		(property "Author" "Antmicro"
			(at 0 0 180)
			(unlocked yes)
			(layer "F.Fab")
			(hide yes)
			(effects
				(font
					(size 1 1)
					(thickness 0.15)
				)
			)
		)
		(property "Voltage" "16V"
			(at 0 0 180)
			(unlocked yes)
			(layer "F.Fab")
			(hide yes)
			(effects
				(font
					(size 1 1)
					(thickness 0.15)
				)
			)
		)
		(property "Dielectric" ""
			(at 0 0 180)
			(unlocked yes)
			(layer "F.Fab")
			(hide yes)
			(effects
				(font
					(size 1 1)
					(thickness 0.15)
				)
			)
		)
		(component_classes
			(class "DCDC_1V8")
		)
		(sheetname "/DCDC/")
		(sheetfile "dcdc.kicad_sch")
		(attr smd)
		(fp_line
			(start -0.15 0.55)
			(end 0.15 0.55)
			(stroke
				(width 0.15)
				(type solid)
			)
			(layer "F.SilkS")
		)
		(fp_line
			(start -0.15 -0.55)
			(end 0.15 -0.55)
			(stroke
				(width 0.15)
				(type solid)
			)
			(layer "F.SilkS")
		)
		(fp_rect
			(start -1.25 -0.65)
			(end 1.25 0.65)
			(stroke
				(width 0.05)
				(type solid)
			)
			(fill no)
			(layer "F.CrtYd")
		)
		(fp_rect
			(start -0.8 -0.45)
			(end 0.8 0.45)
			(stroke
				(width 0.15)
				(type solid)
			)
			(fill no)
			(layer "F.Fab")
		)
		(fp_text user "License: Apache-2.0"
			(at -1.682 5.895 0)
			(layer "F.Fab")
			(effects
				(font
					(size 0.7 0.7)
					(thickness 0.15)
				)
				(justify right top)
			)
		)
		(fp_text user "Author: Antmicro"
			(at -1.682 4.894 0)
			(layer "F.Fab")
			(effects
				(font
					(size 0.7 0.7)
					(thickness 0.15)
				)
				(justify right top)
			)
		)
		(fp_text user "${REFERENCE}"
			(at -1.682 3.895 0)
			(layer "F.Fab")
			(effects
				(font
					(size 0.7 0.7)
					(thickness 0.15)
				)
				(justify right top)
			)
		)
		(pad "1" smd roundrect
			(at -0.7 0 180)
			(size 0.8 1.1)
			(layers "F.Cu" "F.Mask" "F.Paste")
			(roundrect_rratio 0.2)
			(net 17 "/DCDC/1V8_OUT")
			(pintype "passive")
		)
		(pad "2" smd roundrect
			(at 0.7 0 180)
			(size 0.8 1.1)
			(layers "F.Cu" "F.Mask" "F.Paste")
			(roundrect_rratio 0.2)
			(net 1 "GND")
			(pintype "passive")
		)
	)
	(footprint "antmicro-footprints:C_0805_2012Metric"
		(layer "F.Cu")
		(at 174.98 69.11 90)
		(descr "Capacitor SMD 0805")
		(tags "capacitor SMD 0805")
		(property "Reference" "C269"
			(at 1.91 0.52 90)
			(layer "F.SilkS")
			(effects
				(font
					(size 0.7 0.7)
					(thickness 0.15)
				)
				(justify left bottom)
			)
		)
		(property "Value" "C_22u_25V_0805"
			(at -2.055717 1.963152 90)
			(layer "F.Fab")
			(effects
				(font
					(size 0.7 0.7)
					(thickness 0.15)
				)
				(justify left bottom)
			)
		)
		(property "Datasheet" "https://product.samsungsem.com/mlcc/CL21A226MAYNNN.do"
			(at 0 0 90)
			(layer "F.Fab")
			(hide yes)
			(effects
				(font
					(size 1.27 1.27)
					(thickness 0.15)
				)
			)
		)
		(property "Description" "SMT Multilayer Ceramic Capacitor, 22uF, +/-20%, 25V, X5R, 0805 [2012 Metric]"
			(at 0 0 90)
			(layer "F.Fab")
			(hide yes)
			(effects
				(font
					(size 1.27 1.27)
					(thickness 0.15)
				)
			)
		)
		(property "MPN" "CL21A226MAYNNNE"
			(at 0 0 90)
			(unlocked yes)
			(layer "F.Fab")
			(hide yes)
			(effects
				(font
					(size 1 1)
					(thickness 0.15)
				)
			)
		)
		(property "Manufacturer" "Samsung Electro-Mechanics"
			(at 0 0 90)
			(unlocked yes)
			(layer "F.Fab")
			(hide yes)
			(effects
				(font
					(size 1 1)
					(thickness 0.15)
				)
			)
		)
		(property "License" "Apache-2.0"
			(at 0 0 90)
			(unlocked yes)
			(layer "F.Fab")
			(hide yes)
			(effects
				(font
					(size 1 1)
					(thickness 0.15)
				)
			)
		)
		(property "Author" "Antmicro"
			(at 0 0 90)
			(unlocked yes)
			(layer "F.Fab")
			(hide yes)
			(effects
				(font
					(size 1 1)
					(thickness 0.15)
				)
			)
		)
		(property "Val" "22u"
			(at 0 0 90)
			(unlocked yes)
			(layer "F.Fab")
			(hide yes)
			(effects
				(font
					(size 1 1)
					(thickness 0.15)
				)
			)
		)
		(property "Voltage" "25V"
			(at 0 0 90)
			(unlocked yes)
			(layer "F.Fab")
			(hide yes)
			(effects
				(font
					(size 1 1)
					(thickness 0.15)
				)
			)
		)
		(property "Dielectric" "X5R"
			(at 0 0 90)
			(unlocked yes)
			(layer "F.Fab")
			(hide yes)
			(effects
				(font
					(size 1 1)
					(thickness 0.15)
				)
			)
		)
		(property "Public" "False"
			(at 0 0 90)
			(unlocked yes)
			(layer "F.Fab")
			(hide yes)
			(effects
				(font
					(size 1 1)
					(thickness 0.15)
				)
			)
		)
		(component_classes
			(class "DCDC_20V")
		)
		(sheetname "/DCDC/")
		(sheetfile "dcdc.kicad_sch")
		(attr smd)
		(fp_line
			(start -0.3 -0.7)
			(end 0.3 -0.7)
			(stroke
				(width 0.15)
				(type solid)
			)
			(layer "F.SilkS")
		)
		(fp_line
			(start -0.3 0.7)
			(end 0.3 0.7)
			(stroke
				(width 0.15)
				(type solid)
			)
			(layer "F.SilkS")
		)
		(fp_rect
			(start 1.95 -0.9)
			(end -1.95 0.9)
			(stroke
				(width 0.05)
				(type default)
			)
			(fill no)
			(layer "F.CrtYd")
		)
		(fp_rect
			(start -0.95 -0.675)
			(end 0.95 0.675)
			(stroke
				(width 0.15)
				(type solid)
			)
			(fill no)
			(layer "F.Fab")
		)
		(fp_text user "Author: Antmicro"
			(at -1.9 5.947 90)
			(layer "F.Fab")
			(effects
				(font
					(size 0.7 0.7)
					(thickness 0.15)
				)
				(justify left bottom)
			)
		)
		(fp_text user "License: Apache-2.0"
			(at -1.9 4.947 90)
			(layer "F.Fab")
			(effects
				(font
					(size 0.7 0.7)
					(thickness 0.15)
				)
				(justify left bottom)
			)
		)
		(fp_text user "${REFERENCE}"
			(at -1.9 3.947 90)
			(layer "F.Fab")
			(effects
				(font
					(size 0.7 0.7)
					(thickness 0.15)
				)
				(justify left bottom)
			)
		)
		(pad "1" smd roundrect
			(at -1.1 0 90)
			(size 1.2 1.3)
			(layers "F.Cu" "F.Mask" "F.Paste")
			(roundrect_rratio 0.25)
			(net 1 "GND")
			(pintype "passive")
		)
		(pad "2" smd roundrect
			(at 1.1 0 90)
			(size 1.2 1.3)
			(layers "F.Cu" "F.Mask" "F.Paste")
			(roundrect_rratio 0.25)
			(net 13 "VCC")
			(pintype "passive")
		)
	)
	(footprint "antmicro-footprints:R_0402_1005Metric"
		(layer "F.Cu")
		(at 156.6 121.4 180)
		(descr "Resistor SMD 0402")
		(tags "resistor SMD 0402")
		(property "Reference" "R356"
			(at -3.6 0.4 0)
			(layer "F.SilkS")
			(effects
				(font
					(size 0.7 0.7)
					(thickness 0.15)
				)
				(justify right top)
			)
		)
		(property "Value" "R_2k2_0402"
			(at -1.011843 1.772047 0)
			(layer "F.Fab")
			(effects
				(font
					(size 0.7 0.7)
					(thickness 0.15)
				)
				(justify right top)
			)
		)
		(property "Datasheet" "https://www.bourns.com/docs/product-datasheets/cr.pdf"
			(at 0 0 0)
			(layer "F.Fab")
			(hide yes)
			(effects
				(font
					(size 1.27 1.27)
					(thickness 0.15)
				)
			)
		)
		(property "Description" "SMD Chip Resistor, 2.2 kohm, ± 1%, 62.5 mW, 0402 [1005 Metric], Thick Film, General Purpose"
			(at 0 0 0)
			(layer "F.Fab")
			(hide yes)
			(effects
				(font
					(size 1.27 1.27)
					(thickness 0.15)
				)
			)
		)
		(property "MPN" "CR0402-FX-2201GLF"
			(at 0 0 180)
			(unlocked yes)
			(layer "F.Fab")
			(hide yes)
			(effects
				(font
					(size 1 1)
					(thickness 0.15)
				)
			)
		)
		(property "Manufacturer" "Bourns"
			(at 0 0 180)
			(unlocked yes)
			(layer "F.Fab")
			(hide yes)
			(effects
				(font
					(size 1 1)
					(thickness 0.15)
				)
			)
		)
		(property "License" "Apache-2.0"
			(at 0 0 180)
			(unlocked yes)
			(layer "F.Fab")
			(hide yes)
			(effects
				(font
					(size 1 1)
					(thickness 0.15)
				)
			)
		)
		(property "Author" "Antmicro"
			(at 0 0 180)
			(unlocked yes)
			(layer "F.Fab")
			(hide yes)
			(effects
				(font
					(size 1 1)
					(thickness 0.15)
				)
			)
		)
		(property "Val" "2k2"
			(at 0 0 180)
			(unlocked yes)
			(layer "F.Fab")
			(hide yes)
			(effects
				(font
					(size 1 1)
					(thickness 0.15)
				)
			)
		)
		(property "Tolerance" "1%"
			(at 0 0 180)
			(unlocked yes)
			(layer "F.Fab")
			(hide yes)
			(effects
				(font
					(size 1 1)
					(thickness 0.15)
				)
			)
		)
		(sheetname "/SoM_IO/")
		(sheetfile "som_io.kicad_sch")
		(attr smd exclude_from_pos_files exclude_from_bom dnp)
		(fp_rect
			(start -0.925 -0.47)
			(end 0.925 0.47)
			(stroke
				(width 0.05)
				(type default)
			)
			(fill no)
			(layer "F.CrtYd")
		)
		(fp_rect
			(start -0.5 -0.25)
			(end 0.5 0.25)
			(stroke
				(width 0.15)
				(type solid)
			)
			(fill no)
			(layer "F.Fab")
		)
		(fp_text user "Author: Antmicro"
			(at -0.95 4.169 0)
			(layer "F.Fab")
			(effects
				(font
					(size 0.7 0.7)
					(thickness 0.15)
				)
				(justify right top)
			)
		)
		(fp_text user "${REFERENCE}"
			(at -0.95 3.168 0)
			(layer "F.Fab")
			(effects
				(font
					(size 0.7 0.7)
					(thickness 0.15)
				)
				(justify right top)
			)
		)
		(fp_text user "License: Apache-2.0"
			(at -0.95 5.169 0)
			(layer "F.Fab")
			(effects
				(font
					(size 0.7 0.7)
					(thickness 0.15)
				)
				(justify right top)
			)
		)
		(pad "1" smd roundrect
			(at -0.48 0 180)
			(size 0.59 0.64)
			(layers "F.Cu" "F.Mask" "F.Paste")
			(roundrect_rratio 0.25)
			(net 11 "+1V8")
			(pintype "passive")
		)
		(pad "2" smd roundrect
			(at 0.48 0 180)
			(size 0.59 0.64)
			(layers "F.Cu" "F.Mask" "F.Paste")
			(roundrect_rratio 0.25)
			(net 331 "/SoM_IO/I2C0_SDA_1V8")
			(pintype "passive")
		)
	)
	(footprint "antmicro-footprints:R_0402_1005Metric"
		(layer "F.Cu")
		(at 141.1 135.05 180)
		(descr "Resistor SMD 0402")
		(tags "resistor SMD 0402")
		(property "Reference" "R59"
			(at -1.122484 -0.772697 0)
			(layer "F.SilkS")
			(effects
				(font
					(size 0.7 0.7)
					(thickness 0.15)
				)
				(justify right top)
			)
		)
		(property "Value" "R_470R_0402"
			(at -1.011843 1.772047 0)
			(layer "F.Fab")
			(effects
				(font
					(size 0.7 0.7)
					(thickness 0.15)
				)
				(justify right top)
			)
		)
		(property "Datasheet" "https://www.bourns.com/docs/product-datasheets/cr.pdf"
			(at 0 0 0)
			(layer "F.Fab")
			(hide yes)
			(effects
				(font
					(size 1.27 1.27)
					(thickness 0.15)
				)
			)
		)
		(property "Description" "SMD Chip Resistor, 470 ohm, ± 1%, 62.5 mW, 0402 [1005 Metric], Thick Film, General Purpose"
			(at 0 0 0)
			(layer "F.Fab")
			(hide yes)
			(effects
				(font
					(size 1.27 1.27)
					(thickness 0.15)
				)
			)
		)
		(property "MPN" "CR0402-FX-4700GLF"
			(at 0 0 180)
			(unlocked yes)
			(layer "F.Fab")
			(hide yes)
			(effects
				(font
					(size 1 1)
					(thickness 0.15)
				)
			)
		)
		(property "Manufacturer" "Bourns"
			(at 0 0 180)
			(unlocked yes)
			(layer "F.Fab")
			(hide yes)
			(effects
				(font
					(size 1 1)
					(thickness 0.15)
				)
			)
		)
		(property "License" "Apache-2.0"
			(at 0 0 180)
			(unlocked yes)
			(layer "F.Fab")
			(hide yes)
			(effects
				(font
					(size 1 1)
					(thickness 0.15)
				)
			)
		)
		(property "Author" "Antmicro"
			(at 0 0 180)
			(unlocked yes)
			(layer "F.Fab")
			(hide yes)
			(effects
				(font
					(size 1 1)
					(thickness 0.15)
				)
			)
		)
		(property "Val" "470R"
			(at 0 0 180)
			(unlocked yes)
			(layer "F.Fab")
			(hide yes)
			(effects
				(font
					(size 1 1)
					(thickness 0.15)
				)
			)
		)
		(property "Tolerance" "1%"
			(at 0 0 180)
			(unlocked yes)
			(layer "F.Fab")
			(hide yes)
			(effects
				(font
					(size 1 1)
					(thickness 0.15)
				)
			)
		)
		(sheetname "/SoM_Power/")
		(sheetfile "som_power.kicad_sch")
		(attr smd)
		(fp_rect
			(start -0.925 -0.47)
			(end 0.925 0.47)
			(stroke
				(width 0.05)
				(type default)
			)
			(fill no)
			(layer "F.CrtYd")
		)
		(fp_rect
			(start -0.5 -0.25)
			(end 0.5 0.25)
			(stroke
				(width 0.15)
				(type solid)
			)
			(fill no)
			(layer "F.Fab")
		)
		(fp_text user "License: Apache-2.0"
			(at -0.95 5.169 0)
			(layer "F.Fab")
			(effects
				(font
					(size 0.7 0.7)
					(thickness 0.15)
				)
				(justify right top)
			)
		)
		(fp_text user "${REFERENCE}"
			(at -0.95 3.168 0)
			(layer "F.Fab")
			(effects
				(font
					(size 0.7 0.7)
					(thickness 0.15)
				)
				(justify right top)
			)
		)
		(fp_text user "Author: Antmicro"
			(at -0.95 4.169 0)
			(layer "F.Fab")
			(effects
				(font
					(size 0.7 0.7)
					(thickness 0.15)
				)
				(justify right top)
			)
		)
		(pad "1" smd roundrect
			(at -0.48 0 180)
			(size 0.59 0.64)
			(layers "F.Cu" "F.Mask" "F.Paste")
			(roundrect_rratio 0.25)
			(net 886 "Net-(Q11-D)")
			(pintype "passive")
		)
		(pad "2" smd roundrect
			(at 0.48 0 180)
			(size 0.59 0.64)
			(layers "F.Cu" "F.Mask" "F.Paste")
			(roundrect_rratio 0.25)
			(net 2 "+3V3")
			(pintype "passive")
		)
	)
	(footprint "antmicro-footprints:C_0805_2012Metric"
		(layer "F.Cu")
		(at 169.53 73.32 -90)
		(descr "Capacitor SMD 0805")
		(tags "capacitor SMD 0805")
		(property "Reference" "C293"
			(at 1.78449 -1.468678 90)
			(layer "F.SilkS")
			(effects
				(font
					(size 0.7 0.7)
					(thickness 0.15)
				)
				(justify right top)
			)
		)
		(property "Value" "C_22u_25V_0805"
			(at -2.055717 1.963152 90)
			(layer "F.Fab")
			(effects
				(font
					(size 0.7 0.7)
					(thickness 0.15)
				)
				(justify right top)
			)
		)
		(property "Datasheet" "https://product.samsungsem.com/mlcc/CL21A226MAYNNN.do"
			(at 0 0 90)
			(layer "F.Fab")
			(hide yes)
			(effects
				(font
					(size 1.27 1.27)
					(thickness 0.15)
				)
			)
		)
		(property "Description" "SMT Multilayer Ceramic Capacitor, 22uF, +/-20%, 25V, X5R, 0805 [2012 Metric]"
			(at 0 0 90)
			(layer "F.Fab")
			(hide yes)
			(effects
				(font
					(size 1.27 1.27)
					(thickness 0.15)
				)
			)
		)
		(property "MPN" "CL21A226MAYNNNE"
			(at 0 0 270)
			(unlocked yes)
			(layer "F.Fab")
			(hide yes)
			(effects
				(font
					(size 1 1)
					(thickness 0.15)
				)
			)
		)
		(property "Manufacturer" "Samsung Electro-Mechanics"
			(at 0 0 270)
			(unlocked yes)
			(layer "F.Fab")
			(hide yes)
			(effects
				(font
					(size 1 1)
					(thickness 0.15)
				)
			)
		)
		(property "License" "Apache-2.0"
			(at 0 0 270)
			(unlocked yes)
			(layer "F.Fab")
			(hide yes)
			(effects
				(font
					(size 1 1)
					(thickness 0.15)
				)
			)
		)
		(property "Author" "Antmicro"
			(at 0 0 270)
			(unlocked yes)
			(layer "F.Fab")
			(hide yes)
			(effects
				(font
					(size 1 1)
					(thickness 0.15)
				)
			)
		)
		(property "Val" "22u"
			(at 0 0 270)
			(unlocked yes)
			(layer "F.Fab")
			(hide yes)
			(effects
				(font
					(size 1 1)
					(thickness 0.15)
				)
			)
		)
		(property "Voltage" "25V"
			(at 0 0 270)
			(unlocked yes)
			(layer "F.Fab")
			(hide yes)
			(effects
				(font
					(size 1 1)
					(thickness 0.15)
				)
			)
		)
		(property "Dielectric" "X5R"
			(at 0 0 270)
			(unlocked yes)
			(layer "F.Fab")
			(hide yes)
			(effects
				(font
					(size 1 1)
					(thickness 0.15)
				)
			)
		)
		(property "Public" "False"
			(at 0 0 270)
			(unlocked yes)
			(layer "F.Fab")
			(hide yes)
			(effects
				(font
					(size 1 1)
					(thickness 0.15)
				)
			)
		)
		(component_classes
			(class "DCDC_20V")
		)
		(sheetname "/DCDC/")
		(sheetfile "dcdc.kicad_sch")
		(attr smd)
		(fp_line
			(start -0.3 0.7)
			(end 0.3 0.7)
			(stroke
				(width 0.15)
				(type solid)
			)
			(layer "F.SilkS")
		)
		(fp_line
			(start -0.3 -0.7)
			(end 0.3 -0.7)
			(stroke
				(width 0.15)
				(type solid)
			)
			(layer "F.SilkS")
		)
		(fp_rect
			(start 1.95 -0.9)
			(end -1.95 0.9)
			(stroke
				(width 0.05)
				(type default)
			)
			(fill no)
			(layer "F.CrtYd")
		)
		(fp_rect
			(start -0.95 -0.675)
			(end 0.95 0.675)
			(stroke
				(width 0.15)
				(type solid)
			)
			(fill no)
			(layer "F.Fab")
		)
		(fp_text user "License: Apache-2.0"
			(at -1.9 4.947 90)
			(layer "F.Fab")
			(effects
				(font
					(size 0.7 0.7)
					(thickness 0.15)
				)
				(justify right top)
			)
		)
		(fp_text user "Author: Antmicro"
			(at -1.9 5.947 90)
			(layer "F.Fab")
			(effects
				(font
					(size 0.7 0.7)
					(thickness 0.15)
				)
				(justify right top)
			)
		)
		(fp_text user "${REFERENCE}"
			(at -1.9 3.947 90)
			(layer "F.Fab")
			(effects
				(font
					(size 0.7 0.7)
					(thickness 0.15)
				)
				(justify right top)
			)
		)
		(pad "1" smd roundrect
			(at -1.1 0 270)
			(size 1.2 1.3)
			(layers "F.Cu" "F.Mask" "F.Paste")
			(roundrect_rratio 0.25)
			(net 1 "GND")
			(pintype "passive")
		)
		(pad "2" smd roundrect
			(at 1.1 0 270)
			(size 1.2 1.3)
			(layers "F.Cu" "F.Mask" "F.Paste")
			(roundrect_rratio 0.25)
			(net 1105 "/DCDC/20V_OUT")
			(pintype "passive")
		)
	)
)
